(kicad_pcb
	(version 20260206)
	(generator "pcbnew")
	(generator_version "10.0")
	(general
		(thickness 1.6)
		(legacy_teardrops no)
	)
	(paper "A4")
	(title_block
		(title "12092022_DA0F0TMDCD0_F0T_Management_Board_D_brd_V3_OCP.brd")
		(comment 1 "Grand Teton / footprints 605-609 of 1440")
	)
	(layers
		(0 "F.Cu" signal "TOP")
		(4 "In1.Cu" signal "GND")
		(6 "In2.Cu" signal "IN1")
		(8 "In3.Cu" signal "GND1")
		(10 "In4.Cu" signal "IN2")
		(12 "In5.Cu" signal "VCC")
		(14 "In6.Cu" signal "VCC1")
		(16 "In7.Cu" signal "IN3")
		(18 "In8.Cu" signal "GND2")
		(20 "In9.Cu" signal "IN4")
		(22 "In10.Cu" signal "GND3")
		(2 "B.Cu" signal "BOTTOM")
		(9 "F.Adhes" user "F.Adhesive")
		(11 "B.Adhes" user "B.Adhesive")
		(13 "F.Paste" user "Package Geometry/Pastemask Top")
		(15 "B.Paste" user "Package Geometry/Pastemask Bottom")
		(5 "F.SilkS" user "Ref Des/Silkscreen Top")
		(7 "B.SilkS" user "Ref Des/Silkscreen Bottom")
		(1 "F.Mask" user "Board Geometry/Soldermask Top")
		(3 "B.Mask" user "Board Geometry/Soldermask Bottom")
		(17 "Dwgs.User" user "User.Drawings")
		(19 "Cmts.User" user "User.Comments")
		(21 "Eco1.User" user "User.Eco1")
		(23 "Eco2.User" user "User.Eco2")
		(25 "Edge.Cuts" user "Board Geometry/Outline")
		(27 "Margin" user)
		(31 "F.CrtYd" user "Package Geometry/Place Bound Top")
		(29 "B.CrtYd" user "Package Geometry/Place Bound Bottom")
		(35 "F.Fab" user "Ref Des/Assembly Top")
		(33 "B.Fab" user "Ref Des/Assembly Bottom")
	)
	(footprint ""
		(layer "F.Cu")
		(at 49.67478 -66.25082)
		(property "Reference" "R234"
			(at 0 0 0)
			(layer "F.SilkS")
			(hide yes)
			(effects
				(font
					(size 1.27 1.27)
				)
			)
		)
		(property "Value" ""
			(at 0 0 0)
			(layer "F.Fab")
			(effects
				(font
					(size 1.27 1.27)
				)
			)
		)
		(duplicate_pad_numbers_are_jumpers no)
		(fp_line
			(start -0.7874 -0.4064)
			(end 0.7874 -0.4064)
			(stroke
				(width 0.1524)
				(type default)
			)
			(layer "F.SilkS")
		)
		(fp_line
			(start -0.7874 0.4064)
			(end -0.7874 -0.4064)
			(stroke
				(width 0.1524)
				(type default)
			)
			(layer "F.SilkS")
		)
		(fp_line
			(start 0.7874 -0.4064)
			(end 0.7874 0.4064)
			(stroke
				(width 0.1524)
				(type default)
			)
			(layer "F.SilkS")
		)
		(fp_line
			(start 0.7874 0.4064)
			(end -0.7874 0.4064)
			(stroke
				(width 0.1524)
				(type default)
			)
			(layer "F.SilkS")
		)
		(fp_line
			(start -0.67945 -0.305054)
			(end -0.12065 -0.305054)
			(stroke
				(width 0.1)
				(type default)
			)
			(layer "F.Fab")
		)
		(fp_line
			(start -0.67945 0.3048)
			(end -0.67945 -0.305054)
			(stroke
				(width 0.1)
				(type default)
			)
			(layer "F.Fab")
		)
		(fp_line
			(start -0.12065 -0.305054)
			(end -0.12065 -0.2794)
			(stroke
				(width 0.1)
				(type default)
			)
			(layer "F.Fab")
		)
		(fp_line
			(start -0.12065 -0.2794)
			(end 0.12065 -0.2794)
			(stroke
				(width 0.1)
				(type default)
			)
			(layer "F.Fab")
		)
		(fp_line
			(start -0.12065 0.2794)
			(end -0.12065 0.3048)
			(stroke
				(width 0.1)
				(type default)
			)
			(layer "F.Fab")
		)
		(fp_line
			(start -0.12065 0.3048)
			(end -0.67945 0.3048)
			(stroke
				(width 0.1)
				(type default)
			)
			(layer "F.Fab")
		)
		(fp_line
			(start 0.120396 0.2794)
			(end -0.12065 0.2794)
			(stroke
				(width 0.1)
				(type default)
			)
			(layer "F.Fab")
		)
		(fp_line
			(start 0.120396 0.3048)
			(end 0.120396 0.2794)
			(stroke
				(width 0.1)
				(type default)
			)
			(layer "F.Fab")
		)
		(fp_line
			(start 0.12065 -0.3048)
			(end 0.67945 -0.3048)
			(stroke
				(width 0.1)
				(type default)
			)
			(layer "F.Fab")
		)
		(fp_line
			(start 0.12065 -0.2794)
			(end 0.12065 -0.3048)
			(stroke
				(width 0.1)
				(type default)
			)
			(layer "F.Fab")
		)
		(fp_line
			(start 0.67945 -0.3048)
			(end 0.67945 0.3048)
			(stroke
				(width 0.1)
				(type default)
			)
			(layer "F.Fab")
		)
		(fp_line
			(start 0.67945 0.3048)
			(end 0.120396 0.3048)
			(stroke
				(width 0.1)
				(type default)
			)
			(layer "F.Fab")
		)
		(pad "1" smd circle
			(at -0.40005 0)
			(size 0 0)
			(layers "F.Cu" "F.Mask" "F.Paste")
			(net "GND")
		)
		(pad "2" smd circle
			(at 0.40005 0)
			(size 0 0)
			(layers "F.Cu" "F.Mask" "F.Paste")
			(net "A_BMC_ADCREXT1")
		)
	)
	(footprint ""
		(layer "F.Cu")
		(at 82.0928 -114.681)
		(property "Reference" ""
			(at 0 0 0)
			(layer "F.SilkS")
			(hide yes)
			(effects
				(font
					(size 1.27 1.27)
				)
			)
		)
		(property "Value" ""
			(at 0 0 0)
			(layer "F.Fab")
			(effects
				(font
					(size 1.27 1.27)
				)
			)
		)
		(duplicate_pad_numbers_are_jumpers no)
		(pad "1" smd circle
			(at 0 0)
			(size 0.9906 0.9906)
			(layers "F.Cu" "F.Mask" "F.Paste")
			(net "Net_597")
		)
	)
	(footprint ""
		(layer "F.Cu")
		(at 49.2125 -92.0115 90)
		(property "Reference" "R290"
			(at 0 0 90)
			(layer "F.SilkS")
			(hide yes)
			(effects
				(font
					(size 1.27 1.27)
				)
			)
		)
		(property "Value" ""
			(at 0 0 90)
			(layer "F.Fab")
			(effects
				(font
					(size 1.27 1.27)
				)
			)
		)
		(duplicate_pad_numbers_are_jumpers no)
		(fp_line
			(start 0.7874 -0.4064)
			(end 0.7874 0.4064)
			(stroke
				(width 0.1524)
				(type default)
			)
			(layer "F.SilkS")
		)
		(fp_line
			(start -0.7874 -0.4064)
			(end 0.7874 -0.4064)
			(stroke
				(width 0.1524)
				(type default)
			)
			(layer "F.SilkS")
		)
		(fp_line
			(start 0.7874 0.4064)
			(end -0.7874 0.4064)
			(stroke
				(width 0.1524)
				(type default)
			)
			(layer "F.SilkS")
		)
		(fp_line
			(start -0.7874 0.4064)
			(end -0.7874 -0.4064)
			(stroke
				(width 0.1524)
				(type default)
			)
			(layer "F.SilkS")
		)
		(fp_line
			(start -0.12065 -0.305054)
			(end -0.12065 -0.2794)
			(stroke
				(width 0.1)
				(type default)
			)
			(layer "F.Fab")
		)
		(fp_line
			(start -0.67945 -0.305054)
			(end -0.12065 -0.305054)
			(stroke
				(width 0.1)
				(type default)
			)
			(layer "F.Fab")
		)
		(fp_line
			(start 0.67945 -0.3048)
			(end 0.67945 0.3048)
			(stroke
				(width 0.1)
				(type default)
			)
			(layer "F.Fab")
		)
		(fp_line
			(start 0.12065 -0.3048)
			(end 0.67945 -0.3048)
			(stroke
				(width 0.1)
				(type default)
			)
			(layer "F.Fab")
		)
		(fp_line
			(start 0.12065 -0.2794)
			(end 0.12065 -0.3048)
			(stroke
				(width 0.1)
				(type default)
			)
			(layer "F.Fab")
		)
		(fp_line
			(start -0.12065 -0.2794)
			(end 0.12065 -0.2794)
			(stroke
				(width 0.1)
				(type default)
			)
			(layer "F.Fab")
		)
		(fp_line
			(start 0.120396 0.2794)
			(end -0.12065 0.2794)
			(stroke
				(width 0.1)
				(type default)
			)
			(layer "F.Fab")
		)
		(fp_line
			(start -0.12065 0.2794)
			(end -0.12065 0.3048)
			(stroke
				(width 0.1)
				(type default)
			)
			(layer "F.Fab")
		)
		(fp_line
			(start 0.67945 0.3048)
			(end 0.120396 0.3048)
			(stroke
				(width 0.1)
				(type default)
			)
			(layer "F.Fab")
		)
		(fp_line
			(start 0.120396 0.3048)
			(end 0.120396 0.2794)
			(stroke
				(width 0.1)
				(type default)
			)
			(layer "F.Fab")
		)
		(fp_line
			(start -0.12065 0.3048)
			(end -0.67945 0.3048)
			(stroke
				(width 0.1)
				(type default)
			)
			(layer "F.Fab")
		)
		(fp_line
			(start -0.67945 0.3048)
			(end -0.67945 -0.305054)
			(stroke
				(width 0.1)
				(type default)
			)
			(layer "F.Fab")
		)
		(pad "1" smd circle
			(at -0.40005 0 90)
			(size 0 0)
			(layers "F.Cu" "F.Mask" "F.Paste")
			(net "BJT_Q3_B")
		)
		(pad "2" smd circle
			(at 0.40005 0 90)
			(size 0 0)
			(layers "F.Cu" "F.Mask" "F.Paste")
			(net "RST_BMC_EXTRST_R1_N")
		)
	)
	(footprint ""
		(layer "F.Cu")
		(at 26.1874 -83.7438 90)
		(property "Reference" "R169"
			(at 0 0 90)
			(layer "F.SilkS")
			(hide yes)
			(effects
				(font
					(size 1.27 1.27)
				)
			)
		)
		(property "Value" ""
			(at 0 0 90)
			(layer "F.Fab")
			(effects
				(font
					(size 1.27 1.27)
				)
			)
		)
		(duplicate_pad_numbers_are_jumpers no)
		(fp_line
			(start 0.7874 -0.4064)
			(end 0.7874 0.4064)
			(stroke
				(width 0.1524)
				(type default)
			)
			(layer "F.SilkS")
		)
		(fp_line
			(start -0.7874 -0.4064)
			(end 0.7874 -0.4064)
			(stroke
				(width 0.1524)
				(type default)
			)
			(layer "F.SilkS")
		)
		(fp_line
			(start 0.7874 0.4064)
			(end -0.7874 0.4064)
			(stroke
				(width 0.1524)
				(type default)
			)
			(layer "F.SilkS")
		)
		(fp_line
			(start -0.7874 0.4064)
			(end -0.7874 -0.4064)
			(stroke
				(width 0.1524)
				(type default)
			)
			(layer "F.SilkS")
		)
		(fp_line
			(start -0.12065 -0.305054)
			(end -0.12065 -0.2794)
			(stroke
				(width 0.1)
				(type default)
			)
			(layer "F.Fab")
		)
		(fp_line
			(start -0.67945 -0.305054)
			(end -0.12065 -0.305054)
			(stroke
				(width 0.1)
				(type default)
			)
			(layer "F.Fab")
		)
		(fp_line
			(start 0.67945 -0.3048)
			(end 0.67945 0.3048)
			(stroke
				(width 0.1)
				(type default)
			)
			(layer "F.Fab")
		)
		(fp_line
			(start 0.12065 -0.3048)
			(end 0.67945 -0.3048)
			(stroke
				(width 0.1)
				(type default)
			)
			(layer "F.Fab")
		)
		(fp_line
			(start 0.12065 -0.2794)
			(end 0.12065 -0.3048)
			(stroke
				(width 0.1)
				(type default)
			)
			(layer "F.Fab")
		)
		(fp_line
			(start -0.12065 -0.2794)
			(end 0.12065 -0.2794)
			(stroke
				(width 0.1)
				(type default)
			)
			(layer "F.Fab")
		)
		(fp_line
			(start 0.120396 0.2794)
			(end -0.12065 0.2794)
			(stroke
				(width 0.1)
				(type default)
			)
			(layer "F.Fab")
		)
		(fp_line
			(start -0.12065 0.2794)
			(end -0.12065 0.3048)
			(stroke
				(width 0.1)
				(type default)
			)
			(layer "F.Fab")
		)
		(fp_line
			(start 0.67945 0.3048)
			(end 0.120396 0.3048)
			(stroke
				(width 0.1)
				(type default)
			)
			(layer "F.Fab")
		)
		(fp_line
			(start 0.120396 0.3048)
			(end 0.120396 0.2794)
			(stroke
				(width 0.1)
				(type default)
			)
			(layer "F.Fab")
		)
		(fp_line
			(start -0.12065 0.3048)
			(end -0.67945 0.3048)
			(stroke
				(width 0.1)
				(type default)
			)
			(layer "F.Fab")
		)
		(fp_line
			(start -0.67945 0.3048)
			(end -0.67945 -0.305054)
			(stroke
				(width 0.1)
				(type default)
			)
			(layer "F.Fab")
		)
		(pad "1" smd circle
			(at -0.40005 0 90)
			(size 0 0)
			(layers "F.Cu" "F.Mask" "F.Paste")
			(net "P3V3_AUX")
		)
		(pad "2" smd circle
			(at 0.40005 0 90)
			(size 0 0)
			(layers "F.Cu" "F.Mask" "F.Paste")
			(net "RST_PCA9548_SENSOR_N")
		)
	)
	(footprint ""
		(layer "F.Cu")
		(at 27.2796 -69.0626 90)
		(property "Reference" "R849"
			(at 0 0 90)
			(layer "F.SilkS")
			(hide yes)
			(effects
				(font
					(size 1.27 1.27)
				)
			)
		)
		(property "Value" ""
			(at 0 0 90)
			(layer "F.Fab")
			(effects
				(font
					(size 1.27 1.27)
				)
			)
		)
		(duplicate_pad_numbers_are_jumpers no)
		(fp_line
			(start 0.7874 -0.4064)
			(end 0.7874 0.4064)
			(stroke
				(width 0.1524)
				(type default)
			)
			(layer "F.SilkS")
		)
		(fp_line
			(start -0.7874 -0.4064)
			(end 0.7874 -0.4064)
			(stroke
				(width 0.1524)
				(type default)
			)
			(layer "F.SilkS")
		)
		(fp_line
			(start 0.7874 0.4064)
			(end -0.7874 0.4064)
			(stroke
				(width 0.1524)
				(type default)
			)
			(layer "F.SilkS")
		)
		(fp_line
			(start -0.7874 0.4064)
			(end -0.7874 -0.4064)
			(stroke
				(width 0.1524)
				(type default)
			)
			(layer "F.SilkS")
		)
		(fp_line
			(start -0.12065 -0.305054)
			(end -0.12065 -0.2794)
			(stroke
				(width 0.1)
				(type default)
			)
			(layer "F.Fab")
		)
		(fp_line
			(start -0.67945 -0.305054)
			(end -0.12065 -0.305054)
			(stroke
				(width 0.1)
				(type default)
			)
			(layer "F.Fab")
		)
		(fp_line
			(start 0.67945 -0.3048)
			(end 0.67945 0.3048)
			(stroke
				(width 0.1)
				(type default)
			)
			(layer "F.Fab")
		)
		(fp_line
			(start 0.12065 -0.3048)
			(end 0.67945 -0.3048)
			(stroke
				(width 0.1)
				(type default)
			)
			(layer "F.Fab")
		)
		(fp_line
			(start 0.12065 -0.2794)
			(end 0.12065 -0.3048)
			(stroke
				(width 0.1)
				(type default)
			)
			(layer "F.Fab")
		)
		(fp_line
			(start -0.12065 -0.2794)
			(end 0.12065 -0.2794)
			(stroke
				(width 0.1)
				(type default)
			)
			(layer "F.Fab")
		)
		(fp_line
			(start 0.120396 0.2794)
			(end -0.12065 0.2794)
			(stroke
				(width 0.1)
				(type default)
			)
			(layer "F.Fab")
		)
		(fp_line
			(start -0.12065 0.2794)
			(end -0.12065 0.3048)
			(stroke
				(width 0.1)
				(type default)
			)
			(layer "F.Fab")
		)
		(fp_line
			(start 0.67945 0.3048)
			(end 0.120396 0.3048)
			(stroke
				(width 0.1)
				(type default)
			)
			(layer "F.Fab")
		)
		(fp_line
			(start 0.120396 0.3048)
			(end 0.120396 0.2794)
			(stroke
				(width 0.1)
				(type default)
			)
			(layer "F.Fab")
		)
		(fp_line
			(start -0.12065 0.3048)
			(end -0.67945 0.3048)
			(stroke
				(width 0.1)
				(type default)
			)
			(layer "F.Fab")
		)
		(fp_line
			(start -0.67945 0.3048)
			(end -0.67945 -0.305054)
			(stroke
				(width 0.1)
				(type default)
			)
			(layer "F.Fab")
		)
		(pad "1" smd circle
			(at -0.40005 0 90)
			(size 0 0)
			(layers "F.Cu" "F.Mask" "F.Paste")
			(net "SMB_BMC_MM16_R5_SCL")
		)
		(pad "2" smd circle
			(at 0.40005 0 90)
			(size 0 0)
			(layers "F.Cu" "F.Mask" "F.Paste")
			(net "SMB_BMC_MM16_R1_SCL")
		)
	)
)
